(kicad_pcb
	(version 20260206)
	(generator "pcbnew")
	(generator_version "10.0")
	(general
		(thickness 1.6)
		(legacy_teardrops no)
	)
	(paper "A4")
	(title_block
		(title "03242023_DA0F0TMBIJ0_F0T_Motherboard_J_brd_V01_OCP.brd")
		(comment 1 "Grand Teton / footprints 2281-2286 of 6105")
	)
	(layers
		(0 "F.Cu" signal "TOP")
		(4 "In1.Cu" signal "GND")
		(6 "In2.Cu" signal "IN1")
		(8 "In3.Cu" signal "GND1")
		(10 "In4.Cu" signal "IN2")
		(12 "In5.Cu" signal "GND2")
		(14 "In6.Cu" signal "IN3")
		(16 "In7.Cu" signal "GND3")
		(18 "In8.Cu" signal "VCC")
		(20 "In9.Cu" signal "VCC1")
		(22 "In10.Cu" signal "GND4")
		(24 "In11.Cu" signal "IN4")
		(26 "In12.Cu" signal "GND5")
		(28 "In13.Cu" signal "IN5")
		(30 "In14.Cu" signal "GND6")
		(32 "In15.Cu" signal "IN6")
		(34 "In16.Cu" signal "GND7")
		(2 "B.Cu" signal "BOTTOM")
		(9 "F.Adhes" user "F.Adhesive")
		(11 "B.Adhes" user "B.Adhesive")
		(13 "F.Paste" user "Package Geometry/Pastemask Top")
		(15 "B.Paste" user "Package Geometry/Pastemask Bottom")
		(5 "F.SilkS" user "Ref Des/Silkscreen Top")
		(7 "B.SilkS" user "Ref Des/Silkscreen Bottom")
		(1 "F.Mask" user "Board Geometry/Soldermask Top")
		(3 "B.Mask" user "Board Geometry/Soldermask Bottom")
		(17 "Dwgs.User" user "User.Drawings")
		(19 "Cmts.User" user "User.Comments")
		(21 "Eco1.User" user "User.Eco1")
		(23 "Eco2.User" user "User.Eco2")
		(25 "Edge.Cuts" user "Board Geometry/Outline")
		(27 "Margin" user)
		(31 "F.CrtYd" user "Package Geometry/Place Bound Top")
		(29 "B.CrtYd" user "Package Geometry/Place Bound Bottom")
		(35 "F.Fab" user "Ref Des/Assembly Top")
		(33 "B.Fab" user "Ref Des/Assembly Bottom")
	)
	(footprint ""
		(layer "F.Cu")
		(at 93.090492 -74.736706 -90)
		(property "Reference" "R3075"
			(at 0 0 270)
			(layer "F.SilkS")
			(hide yes)
			(effects
				(font
					(size 1.27 1.27)
				)
			)
		)
		(property "Value" ""
			(at 0 0 270)
			(layer "F.Fab")
			(effects
				(font
					(size 1.27 1.27)
				)
			)
		)
		(duplicate_pad_numbers_are_jumpers no)
		(fp_line
			(start -0.7874 0.4064)
			(end -0.7874 -0.4064)
			(stroke
				(width 0.1524)
				(type default)
			)
			(layer "F.SilkS")
		)
		(fp_line
			(start 0.7874 0.4064)
			(end -0.7874 0.4064)
			(stroke
				(width 0.1524)
				(type default)
			)
			(layer "F.SilkS")
		)
		(fp_line
			(start -0.7874 -0.4064)
			(end 0.7874 -0.4064)
			(stroke
				(width 0.1524)
				(type default)
			)
			(layer "F.SilkS")
		)
		(fp_line
			(start 0.7874 -0.4064)
			(end 0.7874 0.4064)
			(stroke
				(width 0.1524)
				(type default)
			)
			(layer "F.SilkS")
		)
		(fp_line
			(start -0.67945 0.3048)
			(end -0.67945 -0.305054)
			(stroke
				(width 0.1)
				(type default)
			)
			(layer "F.Fab")
		)
		(fp_line
			(start -0.12065 0.3048)
			(end -0.67945 0.3048)
			(stroke
				(width 0.1)
				(type default)
			)
			(layer "F.Fab")
		)
		(fp_line
			(start 0.120396 0.3048)
			(end 0.120396 0.2794)
			(stroke
				(width 0.1)
				(type default)
			)
			(layer "F.Fab")
		)
		(fp_line
			(start 0.67945 0.3048)
			(end 0.120396 0.3048)
			(stroke
				(width 0.1)
				(type default)
			)
			(layer "F.Fab")
		)
		(fp_line
			(start -0.12065 0.2794)
			(end -0.12065 0.3048)
			(stroke
				(width 0.1)
				(type default)
			)
			(layer "F.Fab")
		)
		(fp_line
			(start 0.120396 0.2794)
			(end -0.12065 0.2794)
			(stroke
				(width 0.1)
				(type default)
			)
			(layer "F.Fab")
		)
		(fp_line
			(start -0.12065 -0.2794)
			(end 0.12065 -0.2794)
			(stroke
				(width 0.1)
				(type default)
			)
			(layer "F.Fab")
		)
		(fp_line
			(start 0.12065 -0.2794)
			(end 0.12065 -0.3048)
			(stroke
				(width 0.1)
				(type default)
			)
			(layer "F.Fab")
		)
		(fp_line
			(start 0.12065 -0.3048)
			(end 0.67945 -0.3048)
			(stroke
				(width 0.1)
				(type default)
			)
			(layer "F.Fab")
		)
		(fp_line
			(start 0.67945 -0.3048)
			(end 0.67945 0.3048)
			(stroke
				(width 0.1)
				(type default)
			)
			(layer "F.Fab")
		)
		(fp_line
			(start -0.67945 -0.305054)
			(end -0.12065 -0.305054)
			(stroke
				(width 0.1)
				(type default)
			)
			(layer "F.Fab")
		)
		(fp_line
			(start -0.12065 -0.305054)
			(end -0.12065 -0.2794)
			(stroke
				(width 0.1)
				(type default)
			)
			(layer "F.Fab")
		)
		(pad "1" smd circle
			(at -0.40005 0 270)
			(size 0 0)
			(layers "F.Cu" "F.Mask" "F.Paste")
			(net "LED_PWRGD_PS_PWROK_PLD")
		)
		(pad "2" smd circle
			(at 0.40005 0 270)
			(size 0 0)
			(layers "F.Cu" "F.Mask" "F.Paste")
			(net "P3V3_AUX")
		)
	)
	(footprint ""
		(layer "F.Cu")
		(at 183.37403 -397.278352 180)
		(property "Reference" "C2179"
			(at 0 0 180)
			(layer "F.SilkS")
			(hide yes)
			(effects
				(font
					(size 1.27 1.27)
				)
			)
		)
		(property "Value" ""
			(at 0 0 180)
			(layer "F.Fab")
			(effects
				(font
					(size 1.27 1.27)
				)
			)
		)
		(duplicate_pad_numbers_are_jumpers no)
		(fp_line
			(start 0.7874 0.4064)
			(end -0.7874 0.4064)
			(stroke
				(width 0.1524)
				(type default)
			)
			(layer "F.SilkS")
		)
		(fp_line
			(start 0.7874 -0.4064)
			(end 0.7874 0.4064)
			(stroke
				(width 0.1524)
				(type default)
			)
			(layer "F.SilkS")
		)
		(fp_line
			(start -0.7874 0.4064)
			(end -0.7874 -0.4064)
			(stroke
				(width 0.1524)
				(type default)
			)
			(layer "F.SilkS")
		)
		(fp_line
			(start -0.7874 -0.4064)
			(end 0.7874 -0.4064)
			(stroke
				(width 0.1524)
				(type default)
			)
			(layer "F.SilkS")
		)
		(fp_line
			(start 0.67945 0.3048)
			(end 0.120396 0.3048)
			(stroke
				(width 0.1)
				(type default)
			)
			(layer "F.Fab")
		)
		(fp_line
			(start 0.67945 -0.3048)
			(end 0.67945 0.3048)
			(stroke
				(width 0.1)
				(type default)
			)
			(layer "F.Fab")
		)
		(fp_line
			(start 0.12065 -0.2794)
			(end 0.12065 -0.3048)
			(stroke
				(width 0.1)
				(type default)
			)
			(layer "F.Fab")
		)
		(fp_line
			(start 0.12065 -0.3048)
			(end 0.67945 -0.3048)
			(stroke
				(width 0.1)
				(type default)
			)
			(layer "F.Fab")
		)
		(fp_line
			(start 0.120396 0.3048)
			(end 0.120396 0.2794)
			(stroke
				(width 0.1)
				(type default)
			)
			(layer "F.Fab")
		)
		(fp_line
			(start 0.120396 0.2794)
			(end -0.12065 0.2794)
			(stroke
				(width 0.1)
				(type default)
			)
			(layer "F.Fab")
		)
		(fp_line
			(start -0.12065 0.3048)
			(end -0.67945 0.3048)
			(stroke
				(width 0.1)
				(type default)
			)
			(layer "F.Fab")
		)
		(fp_line
			(start -0.12065 0.2794)
			(end -0.12065 0.3048)
			(stroke
				(width 0.1)
				(type default)
			)
			(layer "F.Fab")
		)
		(fp_line
			(start -0.12065 -0.2794)
			(end 0.12065 -0.2794)
			(stroke
				(width 0.1)
				(type default)
			)
			(layer "F.Fab")
		)
		(fp_line
			(start -0.12065 -0.305054)
			(end -0.12065 -0.2794)
			(stroke
				(width 0.1)
				(type default)
			)
			(layer "F.Fab")
		)
		(fp_line
			(start -0.67945 0.3048)
			(end -0.67945 -0.305054)
			(stroke
				(width 0.1)
				(type default)
			)
			(layer "F.Fab")
		)
		(fp_line
			(start -0.67945 -0.305054)
			(end -0.12065 -0.305054)
			(stroke
				(width 0.1)
				(type default)
			)
			(layer "F.Fab")
		)
		(pad "1" smd circle
			(at -0.40005 0 180)
			(size 0 0)
			(layers "F.Cu" "F.Mask" "F.Paste")
			(net "HSC_EN")
		)
		(pad "2" smd circle
			(at 0.40005 0 180)
			(size 0 0)
			(layers "F.Cu" "F.Mask" "F.Paste")
			(net "AGND_HSC")
		)
	)
	(footprint ""
		(layer "F.Cu")
		(at 407.570432 -36.48837)
		(property "Reference" "SW5"
			(at -5.793232 4.106672 0)
			(unlocked yes)
			(layer "F.SilkS")
			(effects
				(font
					(size 0.7874 0.5842)
					(thickness 0.1524)
				)
				(justify left)
			)
		)
		(property "Value" ""
			(at 0 0 0)
			(layer "F.Fab")
			(effects
				(font
					(size 1.27 1.27)
				)
			)
		)
		(duplicate_pad_numbers_are_jumpers no)
		(fp_line
			(start -3.10007 -3.10007)
			(end -3.10007 3.10007)
			(stroke
				(width 0.1524)
				(type default)
			)
			(layer "F.SilkS")
		)
		(fp_line
			(start -3.10007 3.10007)
			(end -3.048 3.10007)
			(stroke
				(width 0.1524)
				(type default)
			)
			(layer "F.SilkS")
		)
		(fp_line
			(start -3.048 -3.10007)
			(end -3.10007 -3.10007)
			(stroke
				(width 0.1524)
				(type default)
			)
			(layer "F.SilkS")
		)
		(fp_line
			(start -1.4478 3.10007)
			(end 1.4478 3.10007)
			(stroke
				(width 0.1524)
				(type default)
			)
			(layer "F.SilkS")
		)
		(fp_line
			(start 1.4478 -3.10007)
			(end -1.4478 -3.10007)
			(stroke
				(width 0.1524)
				(type default)
			)
			(layer "F.SilkS")
		)
		(fp_line
			(start 3.048 3.10007)
			(end 3.10007 3.10007)
			(stroke
				(width 0.1524)
				(type default)
			)
			(layer "F.SilkS")
		)
		(fp_line
			(start 3.10007 -3.10007)
			(end 3.048 -3.10007)
			(stroke
				(width 0.1524)
				(type default)
			)
			(layer "F.SilkS")
		)
		(fp_line
			(start 3.10007 3.10007)
			(end 3.10007 -3.10007)
			(stroke
				(width 0.1524)
				(type default)
			)
			(layer "F.SilkS")
		)
		(fp_circle
			(center 0 0)
			(end 1.75006 0)
			(stroke
				(width 0.1524)
				(type default)
			)
			(fill no)
			(layer "F.SilkS")
		)
		(fp_poly
			(pts
				(xy 2.757932 -5.969) (xy 2.249932 -4.953) (xy 1.741932 -5.969)
			)
			(stroke
				(width 0)
				(type default)
			)
			(fill yes)
			(layer "F.SilkS")
		)
		(fp_line
			(start -3.10007 -3.10007)
			(end -3.10007 3.10007)
			(stroke
				(width 0.1)
				(type default)
			)
			(layer "F.Fab")
		)
		(fp_line
			(start -3.10007 3.10007)
			(end 3.10007 3.10007)
			(stroke
				(width 0.1)
				(type default)
			)
			(layer "F.Fab")
		)
		(fp_line
			(start 3.10007 -3.10007)
			(end -3.10007 -3.10007)
			(stroke
				(width 0.1)
				(type default)
			)
			(layer "F.Fab")
		)
		(fp_line
			(start 3.10007 3.10007)
			(end 3.10007 -3.10007)
			(stroke
				(width 0.1)
				(type default)
			)
			(layer "F.Fab")
		)
		(fp_poly
			(pts
				(xy 2.757932 -5.969) (xy 1.741932 -5.969) (xy 2.249932 -4.953)
			)
			(stroke
				(width 0)
				(type default)
			)
			(fill yes)
			(layer "F.Fab")
		)
		(pad "1" smd rect
			(at 2.249932 -3.9751)
			(size 1.3208 1.5494)
			(layers "F.Cu" "F.Mask" "F.Paste")
			(net "PD_RST_RTCRST_N")
		)
		(pad "2" smd rect
			(at 2.249932 3.9751)
			(size 1.3208 1.5494)
			(layers "F.Cu" "F.Mask" "F.Paste")
			(net "PD_RST_RTCRST_N")
		)
		(pad "3" smd rect
			(at -2.249932 -3.9751)
			(size 1.3208 1.5494)
			(layers "F.Cu" "F.Mask" "F.Paste")
			(net "RST_RTCRST_N")
		)
		(pad "4" smd rect
			(at -2.249932 3.9751)
			(size 1.3208 1.5494)
			(layers "F.Cu" "F.Mask" "F.Paste")
			(net "RST_RTCRST_N")
		)
	)
	(footprint ""
		(layer "F.Cu")
		(at 96.57588 -57.241948 180)
		(property "Reference" "R1374"
			(at 0 0 180)
			(layer "F.SilkS")
			(hide yes)
			(effects
				(font
					(size 1.27 1.27)
				)
			)
		)
		(property "Value" ""
			(at 0 0 180)
			(layer "F.Fab")
			(effects
				(font
					(size 1.27 1.27)
				)
			)
		)
		(duplicate_pad_numbers_are_jumpers no)
		(fp_line
			(start 0.7874 0.4064)
			(end -0.7874 0.4064)
			(stroke
				(width 0.1524)
				(type default)
			)
			(layer "F.SilkS")
		)
		(fp_line
			(start 0.7874 -0.4064)
			(end 0.7874 0.4064)
			(stroke
				(width 0.1524)
				(type default)
			)
			(layer "F.SilkS")
		)
		(fp_line
			(start -0.7874 0.4064)
			(end -0.7874 -0.4064)
			(stroke
				(width 0.1524)
				(type default)
			)
			(layer "F.SilkS")
		)
		(fp_line
			(start -0.7874 -0.4064)
			(end 0.7874 -0.4064)
			(stroke
				(width 0.1524)
				(type default)
			)
			(layer "F.SilkS")
		)
		(fp_line
			(start 0.67945 0.3048)
			(end 0.120396 0.3048)
			(stroke
				(width 0.1)
				(type default)
			)
			(layer "F.Fab")
		)
		(fp_line
			(start 0.67945 -0.3048)
			(end 0.67945 0.3048)
			(stroke
				(width 0.1)
				(type default)
			)
			(layer "F.Fab")
		)
		(fp_line
			(start 0.12065 -0.2794)
			(end 0.12065 -0.3048)
			(stroke
				(width 0.1)
				(type default)
			)
			(layer "F.Fab")
		)
		(fp_line
			(start 0.12065 -0.3048)
			(end 0.67945 -0.3048)
			(stroke
				(width 0.1)
				(type default)
			)
			(layer "F.Fab")
		)
		(fp_line
			(start 0.120396 0.3048)
			(end 0.120396 0.2794)
			(stroke
				(width 0.1)
				(type default)
			)
			(layer "F.Fab")
		)
		(fp_line
			(start 0.120396 0.2794)
			(end -0.12065 0.2794)
			(stroke
				(width 0.1)
				(type default)
			)
			(layer "F.Fab")
		)
		(fp_line
			(start -0.12065 0.3048)
			(end -0.67945 0.3048)
			(stroke
				(width 0.1)
				(type default)
			)
			(layer "F.Fab")
		)
		(fp_line
			(start -0.12065 0.2794)
			(end -0.12065 0.3048)
			(stroke
				(width 0.1)
				(type default)
			)
			(layer "F.Fab")
		)
		(fp_line
			(start -0.12065 -0.2794)
			(end 0.12065 -0.2794)
			(stroke
				(width 0.1)
				(type default)
			)
			(layer "F.Fab")
		)
		(fp_line
			(start -0.12065 -0.305054)
			(end -0.12065 -0.2794)
			(stroke
				(width 0.1)
				(type default)
			)
			(layer "F.Fab")
		)
		(fp_line
			(start -0.67945 0.3048)
			(end -0.67945 -0.305054)
			(stroke
				(width 0.1)
				(type default)
			)
			(layer "F.Fab")
		)
		(fp_line
			(start -0.67945 -0.305054)
			(end -0.12065 -0.305054)
			(stroke
				(width 0.1)
				(type default)
			)
			(layer "F.Fab")
		)
		(pad "1" smd circle
			(at -0.40005 0 180)
			(size 0 0)
			(layers "F.Cu" "F.Mask" "F.Paste")
			(net "PD_JTAG_BMC_NTRST_N")
		)
		(pad "2" smd circle
			(at 0.40005 0 180)
			(size 0 0)
			(layers "F.Cu" "F.Mask" "F.Paste")
			(net "GND")
		)
	)
	(footprint ""
		(layer "F.Cu")
		(at 100.158296 -423.579798 -90)
		(property "Reference" "U272"
			(at 1.16078 -3.199384 0)
			(unlocked yes)
			(layer "F.SilkS")
			(effects
				(font
					(size 0.7874 0.5842)
					(thickness 0.1524)
				)
				(justify left)
			)
		)
		(property "Value" ""
			(at 0 0 270)
			(layer "F.Fab")
			(effects
				(font
					(size 1.27 1.27)
				)
			)
		)
		(duplicate_pad_numbers_are_jumpers no)
		(fp_line
			(start -3.447796 2.500122)
			(end 3.447796 2.500122)
			(stroke
				(width 0.1524)
				(type default)
			)
			(layer "F.SilkS")
		)
		(fp_line
			(start 3.447796 2.500122)
			(end 3.447796 -2.500122)
			(stroke
				(width 0.1524)
				(type default)
			)
			(layer "F.SilkS")
		)
		(fp_line
			(start 0 -1.016)
			(end -1.484122 -2.500122)
			(stroke
				(width 0.1524)
				(type default)
			)
			(layer "F.SilkS")
		)
		(fp_line
			(start -3.447796 -2.500122)
			(end -3.447796 2.500122)
			(stroke
				(width 0.1524)
				(type default)
			)
			(layer "F.SilkS")
		)
		(fp_line
			(start -1.484122 -2.500122)
			(end -3.447796 -2.500122)
			(stroke
				(width 0.1524)
				(type default)
			)
			(layer "F.SilkS")
		)
		(fp_line
			(start 1.484122 -2.500122)
			(end 0 -1.016)
			(stroke
				(width 0.1524)
				(type default)
			)
			(layer "F.SilkS")
		)
		(fp_line
			(start 3.447796 -2.500122)
			(end 1.484122 -2.500122)
			(stroke
				(width 0.1524)
				(type default)
			)
			(layer "F.SilkS")
		)
		(fp_poly
			(pts
				(xy -4.6609 -2.47396) (xy -3.6449 -1.96596) (xy -4.6609 -1.45796)
			)
			(stroke
				(width 0)
				(type default)
			)
			(fill yes)
			(layer "F.SilkS")
		)
		(fp_line
			(start -1.999996 2.500122)
			(end 1.999996 2.500122)
			(stroke
				(width 0.1)
				(type default)
			)
			(layer "F.Fab")
		)
		(fp_line
			(start 1.999996 2.500122)
			(end 1.999996 -2.500122)
			(stroke
				(width 0.1)
				(type default)
			)
			(layer "F.Fab")
		)
		(fp_line
			(start -1.999996 -2.500122)
			(end -1.999996 2.500122)
			(stroke
				(width 0.1)
				(type default)
			)
			(layer "F.Fab")
		)
		(fp_line
			(start 1.999996 -2.500122)
			(end -1.999996 -2.500122)
			(stroke
				(width 0.1)
				(type default)
			)
			(layer "F.Fab")
		)
		(fp_poly
			(pts
				(xy -4.5974 -2.413) (xy -4.5974 -1.397) (xy -3.5814 -1.905)
			)
			(stroke
				(width 0)
				(type default)
			)
			(fill yes)
			(layer "F.Fab")
		)
		(pad "1" smd rect
			(at -2.649982 -1.905 180)
			(size 0.6096 1.3208)
			(layers "F.Cu" "F.Mask" "F.Paste")
			(net "SMB_LM75_2_3V3AUX_SDA_R1")
		)
		(pad "2" smd rect
			(at -2.649982 -0.635 180)
			(size 0.6096 1.3208)
			(layers "F.Cu" "F.Mask" "F.Paste")
			(net "SMB_LM75_2_3V3AUX_SCL_R1")
		)
		(pad "3" smd rect
			(at -2.649982 0.635 180)
			(size 0.6096 1.3208)
			(layers "F.Cu" "F.Mask" "F.Paste")
			(net "FM_LM75_2_ALERT_N")
		)
		(pad "4" smd rect
			(at -2.649982 1.905 180)
			(size 0.6096 1.3208)
			(layers "F.Cu" "F.Mask" "F.Paste")
			(net "GND")
		)
		(pad "5" smd rect
			(at 2.649982 1.905 180)
			(size 0.6096 1.3208)
			(layers "F.Cu" "F.Mask" "F.Paste")
			(net "U272_2_ADD2")
		)
		(pad "6" smd rect
			(at 2.649982 0.635 180)
			(size 0.6096 1.3208)
			(layers "F.Cu" "F.Mask" "F.Paste")
			(net "U272_2_ADD1")
		)
		(pad "7" smd rect
			(at 2.649982 -0.635 180)
			(size 0.6096 1.3208)
			(layers "F.Cu" "F.Mask" "F.Paste")
			(net "U272_2_ADD0")
		)
		(pad "8" smd rect
			(at 2.649982 -1.905 180)
			(size 0.6096 1.3208)
			(layers "F.Cu" "F.Mask" "F.Paste")
			(net "P3V3_AUX")
		)
	)
	(footprint ""
		(layer "F.Cu")
		(at 331.099668 -76.153518 90)
		(property "Reference" "R4305"
			(at 0 0 90)
			(layer "F.SilkS")
			(hide yes)
			(effects
				(font
					(size 1.27 1.27)
				)
			)
		)
		(property "Value" ""
			(at 0 0 90)
			(layer "F.Fab")
			(effects
				(font
					(size 1.27 1.27)
				)
			)
		)
		(duplicate_pad_numbers_are_jumpers no)
		(fp_line
			(start 0.7874 -0.4064)
			(end 0.7874 0.4064)
			(stroke
				(width 0.1524)
				(type default)
			)
			(layer "F.SilkS")
		)
		(fp_line
			(start -0.7874 -0.4064)
			(end 0.7874 -0.4064)
			(stroke
				(width 0.1524)
				(type default)
			)
			(layer "F.SilkS")
		)
		(fp_line
			(start 0.7874 0.4064)
			(end -0.7874 0.4064)
			(stroke
				(width 0.1524)
				(type default)
			)
			(layer "F.SilkS")
		)
		(fp_line
			(start -0.7874 0.4064)
			(end -0.7874 -0.4064)
			(stroke
				(width 0.1524)
				(type default)
			)
			(layer "F.SilkS")
		)
		(fp_line
			(start -0.12065 -0.305054)
			(end -0.12065 -0.2794)
			(stroke
				(width 0.1)
				(type default)
			)
			(layer "F.Fab")
		)
		(fp_line
			(start -0.67945 -0.305054)
			(end -0.12065 -0.305054)
			(stroke
				(width 0.1)
				(type default)
			)
			(layer "F.Fab")
		)
		(fp_line
			(start 0.67945 -0.3048)
			(end 0.67945 0.3048)
			(stroke
				(width 0.1)
				(type default)
			)
			(layer "F.Fab")
		)
		(fp_line
			(start 0.12065 -0.3048)
			(end 0.67945 -0.3048)
			(stroke
				(width 0.1)
				(type default)
			)
			(layer "F.Fab")
		)
		(fp_line
			(start 0.12065 -0.2794)
			(end 0.12065 -0.3048)
			(stroke
				(width 0.1)
				(type default)
			)
			(layer "F.Fab")
		)
		(fp_line
			(start -0.12065 -0.2794)
			(end 0.12065 -0.2794)
			(stroke
				(width 0.1)
				(type default)
			)
			(layer "F.Fab")
		)
		(fp_line
			(start 0.120396 0.2794)
			(end -0.12065 0.2794)
			(stroke
				(width 0.1)
				(type default)
			)
			(layer "F.Fab")
		)
		(fp_line
			(start -0.12065 0.2794)
			(end -0.12065 0.3048)
			(stroke
				(width 0.1)
				(type default)
			)
			(layer "F.Fab")
		)
		(fp_line
			(start 0.67945 0.3048)
			(end 0.120396 0.3048)
			(stroke
				(width 0.1)
				(type default)
			)
			(layer "F.Fab")
		)
		(fp_line
			(start 0.120396 0.3048)
			(end 0.120396 0.2794)
			(stroke
				(width 0.1)
				(type default)
			)
			(layer "F.Fab")
		)
		(fp_line
			(start -0.12065 0.3048)
			(end -0.67945 0.3048)
			(stroke
				(width 0.1)
				(type default)
			)
			(layer "F.Fab")
		)
		(fp_line
			(start -0.67945 0.3048)
			(end -0.67945 -0.305054)
			(stroke
				(width 0.1)
				(type default)
			)
			(layer "F.Fab")
		)
		(pad "1" smd circle
			(at -0.40005 0 90)
			(size 0 0)
			(layers "F.Cu" "F.Mask" "F.Paste")
			(net "CLK_100M_PE_M2_0_R_DP")
		)
		(pad "2" smd circle
			(at 0.40005 0 90)
			(size 0 0)
			(layers "F.Cu" "F.Mask" "F.Paste")
			(net "CLK_100M_PE_M2_0_DP")
		)
	)
)
